(kicad_pcb
	(version 20260206)
	(generator "pcbnew")
	(generator_version "10.0")
	(general
		(thickness 1.6)
		(legacy_teardrops no)
	)
	(paper "A4")
	(title_block
		(title "v2-pdb — ms_pdb_v2.brd")
		(comment 1 "Open CloudServer (Microsoft) / footprint 347 of 348 (J13), pads 1-46 of 46")
	)
	(layers
		(0 "F.Cu" signal "TOP")
		(4 "In1.Cu" signal "GND")
		(6 "In2.Cu" signal "IN1")
		(8 "In3.Cu" signal "VCC")
		(10 "In4.Cu" signal "VCC1")
		(12 "In5.Cu" signal "IN2")
		(14 "In6.Cu" signal "GND1")
		(2 "B.Cu" signal "BOTTOM")
		(9 "F.Adhes" user "F.Adhesive")
		(11 "B.Adhes" user "B.Adhesive")
		(13 "F.Paste" user "Package Geometry/Pastemask Top")
		(15 "B.Paste" user "Package Geometry/Pastemask Bottom")
		(5 "F.SilkS" user "Ref Des/Silkscreen Top")
		(7 "B.SilkS" user "Ref Des/Silkscreen Bottom")
		(1 "F.Mask" user "Board Geometry/Soldermask Top")
		(3 "B.Mask" user "Board Geometry/Soldermask Bottom")
		(17 "Dwgs.User" user "User.Drawings")
		(19 "Cmts.User" user "User.Comments")
		(21 "Eco1.User" user "User.Eco1")
		(23 "Eco2.User" user "User.Eco2")
		(25 "Edge.Cuts" user "Board Geometry/Outline")
		(27 "Margin" user)
		(31 "F.CrtYd" user "Package Geometry/Place Bound Top")
		(29 "B.CrtYd" user "Package Geometry/Place Bound Bottom")
		(35 "F.Fab" user "Ref Des/Assembly Top")
		(33 "B.Fab" user "Ref Des/Assembly Bottom")
	)
	(footprint ""
		(layer "B.Cu")
		(at 44.03979 -274.96008 90)
		(property "Reference" "J13"
			(at 6.540246 -4.559808 0)
			(unlocked yes)
			(layer "B.SilkS")
			(effects
				(font
					(size 0.7874 0.5842)
					(thickness 0.1524)
				)
				(justify left mirror)
			)
		)
		(property "Value" ""
			(at 0 0 90)
			(layer "B.Fab")
			(effects
				(font
					(size 1.27 1.27)
				)
				(justify mirror)
			)
		)
		(duplicate_pad_numbers_are_jumpers no)
		(pad "" np_thru_hole circle
			(at -1.35001 -2.54)
			(size 2.5146 2.5146)
			(drill 2.5146)
			(layers "*.Cu" "*.Mask")
			(clearance 0.381)
			(thermal_gap 0.381)
		)
		(pad "" np_thru_hole circle
			(at 0 50.8)
			(size 2.5146 2.5146)
			(drill 2.5146)
			(layers "*.Cu" "*.Mask")
			(clearance 0.381)
			(thermal_gap 0.381)
		)
		(pad "P1" thru_hole rect
			(at 0 0)
			(size 1.1684 1.1684)
			(drill 0.762)
			(layers "*.Cu" "*.Mask")
			(remove_unused_layers no)
			(net "GND")
			(clearance 0.0508)
			(padstack
				(mode front_inner_back)
				(layer "Inner"
					(shape circle)
					(size 1.1684 1.1684)
					(clearance 0.0508)
				)
				(layer "B.Cu"
					(shape rect)
					(size 1.1684 1.1684)
					(thermal_gap 0.0508)
					(clearance 0.0508)
				)
			)
		)
		(pad "P2" thru_hole circle
			(at 0 2.54)
			(size 1.1684 1.1684)
			(drill 0.762)
			(layers "*.Cu" "*.Mask")
			(remove_unused_layers no)
			(net "GND")
			(clearance 0.0508)
			(thermal_gap 0.0508)
		)
		(pad "P3" thru_hole circle
			(at 0 5.08)
			(size 1.1684 1.1684)
			(drill 0.762)
			(layers "*.Cu" "*.Mask")
			(remove_unused_layers no)
			(net "GND")
			(clearance 0.0508)
			(thermal_gap 0.0508)
		)
		(pad "P4" thru_hole circle
			(at 0 7.62)
			(size 1.1684 1.1684)
			(drill 0.762)
			(layers "*.Cu" "*.Mask")
			(remove_unused_layers no)
			(net "GND")
			(clearance 0.0508)
			(thermal_gap 0.0508)
		)
		(pad "P5" thru_hole circle
			(at 0 10.16)
			(size 1.1684 1.1684)
			(drill 0.762)
			(layers "*.Cu" "*.Mask")
			(remove_unused_layers no)
			(net "GND")
			(clearance 0.0508)
			(thermal_gap 0.0508)
		)
		(pad "P6" thru_hole circle
			(at 0 12.7)
			(size 1.1684 1.1684)
			(drill 0.762)
			(layers "*.Cu" "*.Mask")
			(remove_unused_layers no)
			(net "GND")
			(clearance 0.0508)
			(thermal_gap 0.0508)
		)
		(pad "P7" thru_hole circle
			(at 0 15.24)
			(size 1.1684 1.1684)
			(drill 0.762)
			(layers "*.Cu" "*.Mask")
			(remove_unused_layers no)
			(net "GND")
			(clearance 0.0508)
			(thermal_gap 0.0508)
		)
		(pad "P8" thru_hole circle
			(at 0 17.78)
			(size 1.1684 1.1684)
			(drill 0.762)
			(layers "*.Cu" "*.Mask")
			(remove_unused_layers no)
			(net "GND")
			(clearance 0.0508)
			(thermal_gap 0.0508)
		)
		(pad "P9" thru_hole circle
			(at 0 20.32)
			(size 1.1684 1.1684)
			(drill 0.762)
			(layers "*.Cu" "*.Mask")
			(remove_unused_layers no)
			(net "P12V")
			(clearance 0.0508)
			(thermal_gap 0.0508)
		)
		(pad "P10" thru_hole circle
			(at 0 22.86)
			(size 1.1684 1.1684)
			(drill 0.762)
			(layers "*.Cu" "*.Mask")
			(remove_unused_layers no)
			(net "P12V")
			(clearance 0.0508)
			(thermal_gap 0.0508)
		)
		(pad "P11" thru_hole circle
			(at 0 25.4)
			(size 1.1684 1.1684)
			(drill 0.762)
			(layers "*.Cu" "*.Mask")
			(remove_unused_layers no)
			(net "P12V")
			(clearance 0.0508)
			(thermal_gap 0.0508)
		)
		(pad "P12" thru_hole circle
			(at 0 27.94)
			(size 1.1684 1.1684)
			(drill 0.762)
			(layers "*.Cu" "*.Mask")
			(remove_unused_layers no)
			(net "P12V")
			(clearance 0.0508)
			(thermal_gap 0.0508)
		)
		(pad "P13" thru_hole circle
			(at 0 30.48)
			(size 1.1684 1.1684)
			(drill 0.762)
			(layers "*.Cu" "*.Mask")
			(remove_unused_layers no)
			(net "P12V")
			(clearance 0.0508)
			(thermal_gap 0.0508)
		)
		(pad "P14" thru_hole circle
			(at 0 33.02)
			(size 1.1684 1.1684)
			(drill 0.762)
			(layers "*.Cu" "*.Mask")
			(remove_unused_layers no)
			(net "P12V")
			(clearance 0.0508)
			(thermal_gap 0.0508)
		)
		(pad "P15" thru_hole circle
			(at 0 35.56)
			(size 1.1684 1.1684)
			(drill 0.762)
			(layers "*.Cu" "*.Mask")
			(remove_unused_layers no)
			(net "P12V")
			(clearance 0.0508)
			(thermal_gap 0.0508)
		)
		(pad "P16" thru_hole circle
			(at 0 38.1)
			(size 1.1684 1.1684)
			(drill 0.762)
			(layers "*.Cu" "*.Mask")
			(remove_unused_layers no)
			(net "P12V")
			(clearance 0.0508)
			(thermal_gap 0.0508)
		)
		(pad "P17" thru_hole circle
			(at -2.70002 38.1)
			(size 1.1684 1.1684)
			(drill 0.762)
			(layers "*.Cu" "*.Mask")
			(remove_unused_layers no)
			(net "P12V")
			(clearance 0.0508)
			(thermal_gap 0.0508)
		)
		(pad "P18" thru_hole circle
			(at -2.70002 35.56)
			(size 1.1684 1.1684)
			(drill 0.762)
			(layers "*.Cu" "*.Mask")
			(remove_unused_layers no)
			(net "P12V")
			(clearance 0.0508)
			(thermal_gap 0.0508)
		)
		(pad "P19" thru_hole circle
			(at -2.70002 33.02)
			(size 1.1684 1.1684)
			(drill 0.762)
			(layers "*.Cu" "*.Mask")
			(remove_unused_layers no)
			(net "P12V")
			(clearance 0.0508)
			(thermal_gap 0.0508)
		)
		(pad "P20" thru_hole circle
			(at -2.70002 30.48)
			(size 1.1684 1.1684)
			(drill 0.762)
			(layers "*.Cu" "*.Mask")
			(remove_unused_layers no)
			(net "P12V")
			(clearance 0.0508)
			(thermal_gap 0.0508)
		)
		(pad "P21" thru_hole circle
			(at -2.70002 27.94)
			(size 1.1684 1.1684)
			(drill 0.762)
			(layers "*.Cu" "*.Mask")
			(remove_unused_layers no)
			(net "P12V")
			(clearance 0.0508)
			(thermal_gap 0.0508)
		)
		(pad "P22" thru_hole circle
			(at -2.70002 25.4)
			(size 1.1684 1.1684)
			(drill 0.762)
			(layers "*.Cu" "*.Mask")
			(remove_unused_layers no)
			(net "P12V")
			(clearance 0.0508)
			(thermal_gap 0.0508)
		)
		(pad "P23" thru_hole circle
			(at -2.70002 22.86)
			(size 1.1684 1.1684)
			(drill 0.762)
			(layers "*.Cu" "*.Mask")
			(remove_unused_layers no)
			(net "P12V")
			(clearance 0.0508)
			(thermal_gap 0.0508)
		)
		(pad "P24" thru_hole circle
			(at -2.70002 20.32)
			(size 1.1684 1.1684)
			(drill 0.762)
			(layers "*.Cu" "*.Mask")
			(remove_unused_layers no)
			(net "P12V")
			(clearance 0.0508)
			(thermal_gap 0.0508)
		)
		(pad "P25" thru_hole circle
			(at -2.70002 17.78)
			(size 1.1684 1.1684)
			(drill 0.762)
			(layers "*.Cu" "*.Mask")
			(remove_unused_layers no)
			(net "GND")
			(clearance 0.0508)
			(thermal_gap 0.0508)
		)
		(pad "P26" thru_hole circle
			(at -2.70002 15.24)
			(size 1.1684 1.1684)
			(drill 0.762)
			(layers "*.Cu" "*.Mask")
			(remove_unused_layers no)
			(net "GND")
			(clearance 0.0508)
			(thermal_gap 0.0508)
		)
		(pad "P27" thru_hole circle
			(at -2.70002 12.7)
			(size 1.1684 1.1684)
			(drill 0.762)
			(layers "*.Cu" "*.Mask")
			(remove_unused_layers no)
			(net "GND")
			(clearance 0.0508)
			(thermal_gap 0.0508)
		)
		(pad "P28" thru_hole circle
			(at -2.70002 10.16)
			(size 1.1684 1.1684)
			(drill 0.762)
			(layers "*.Cu" "*.Mask")
			(remove_unused_layers no)
			(net "GND")
			(clearance 0.0508)
			(thermal_gap 0.0508)
		)
		(pad "P29" thru_hole circle
			(at -2.70002 7.62)
			(size 1.1684 1.1684)
			(drill 0.762)
			(layers "*.Cu" "*.Mask")
			(remove_unused_layers no)
			(net "GND")
			(clearance 0.0508)
			(thermal_gap 0.0508)
		)
		(pad "P30" thru_hole circle
			(at -2.70002 5.08)
			(size 1.1684 1.1684)
			(drill 0.762)
			(layers "*.Cu" "*.Mask")
			(remove_unused_layers no)
			(net "GND")
			(clearance 0.0508)
			(thermal_gap 0.0508)
		)
		(pad "P31" thru_hole circle
			(at -2.70002 2.54)
			(size 1.1684 1.1684)
			(drill 0.762)
			(layers "*.Cu" "*.Mask")
			(remove_unused_layers no)
			(net "GND")
			(clearance 0.0508)
			(thermal_gap 0.0508)
		)
		(pad "P32" thru_hole circle
			(at -2.70002 0)
			(size 1.1684 1.1684)
			(drill 0.762)
			(layers "*.Cu" "*.Mask")
			(remove_unused_layers no)
			(net "GND")
			(clearance 0.0508)
			(thermal_gap 0.0508)
		)
		(pad "S1" thru_hole circle
			(at 0.55499 41.60012)
			(size 1.1684 1.1684)
			(drill 0.762)
			(layers "*.Cu" "*.Mask")
			(remove_unused_layers no)
			(net "T7_BLAD1_TXD")
			(clearance 0.0508)
			(thermal_gap 0.0508)
		)
		(pad "S2" thru_hole circle
			(at -0.71501 42.87012)
			(size 1.1684 1.1684)
			(drill 0.762)
			(layers "*.Cu" "*.Mask")
			(remove_unused_layers no)
			(net "T7_BLAD1_RXD")
			(clearance 0.0508)
			(thermal_gap 0.0508)
		)
		(pad "S3" thru_hole circle
			(at 0.55499 44.14012)
			(size 1.1684 1.1684)
			(drill 0.762)
			(layers "*.Cu" "*.Mask")
			(remove_unused_layers no)
			(net "T7_BLAD1_EN")
			(clearance 0.0508)
			(thermal_gap 0.0508)
		)
		(pad "S4" thru_hole circle
			(at -0.71501 45.41012)
			(size 1.1684 1.1684)
			(drill 0.762)
			(layers "*.Cu" "*.Mask")
			(remove_unused_layers no)
			(net "B13_PSU_ALERT_N")
			(clearance 0.0508)
			(thermal_gap 0.0508)
		)
		(pad "S5" thru_hole circle
			(at 0.55499 46.68012)
			(size 1.1684 1.1684)
			(drill 0.762)
			(layers "*.Cu" "*.Mask")
			(remove_unused_layers no)
			(net "T7_BLAD2_TXD")
			(clearance 0.0508)
			(thermal_gap 0.0508)
		)
		(pad "S6" thru_hole circle
			(at -0.71501 47.95012)
			(size 1.1684 1.1684)
			(drill 0.762)
			(layers "*.Cu" "*.Mask")
			(remove_unused_layers no)
			(net "T7_BLAD2_RXD")
			(clearance 0.0508)
			(thermal_gap 0.0508)
		)
		(pad "S7" thru_hole circle
			(at -3.25501 47.95012)
			(size 1.1684 1.1684)
			(drill 0.762)
			(layers "*.Cu" "*.Mask")
			(remove_unused_layers no)
			(net "T7_BLAD4_RXD")
			(clearance 0.0508)
			(thermal_gap 0.0508)
		)
		(pad "S8" thru_hole circle
			(at -1.98501 46.68012)
			(size 1.1684 1.1684)
			(drill 0.762)
			(layers "*.Cu" "*.Mask")
			(remove_unused_layers no)
			(net "T7_BLAD4_TXD")
			(clearance 0.0508)
			(thermal_gap 0.0508)
		)
		(pad "S9" thru_hole circle
			(at -3.25501 45.41012)
			(size 1.1684 1.1684)
			(drill 0.762)
			(layers "*.Cu" "*.Mask")
			(remove_unused_layers no)
			(net "B14_PSU_ALERT_N")
			(clearance 0.0508)
			(thermal_gap 0.0508)
		)
		(pad "S10" thru_hole circle
			(at -1.98501 44.14012)
			(size 1.1684 1.1684)
			(drill 0.762)
			(layers "*.Cu" "*.Mask")
			(remove_unused_layers no)
			(net "T7_BLAD3_EN")
			(clearance 0.0508)
			(thermal_gap 0.0508)
		)
		(pad "S11" thru_hole circle
			(at -3.25501 42.87012)
			(size 1.1684 1.1684)
			(drill 0.762)
			(layers "*.Cu" "*.Mask")
			(remove_unused_layers no)
			(net "T7_BLAD3_RXD")
			(clearance 0.0508)
			(thermal_gap 0.0508)
		)
		(pad "S12" thru_hole circle
			(at -1.98501 41.60012)
			(size 1.1684 1.1684)
			(drill 0.762)
			(layers "*.Cu" "*.Mask")
			(remove_unused_layers no)
			(net "T7_BLAD3_TXD")
			(clearance 0.0508)
			(thermal_gap 0.0508)
		)
	)
)
